(kicad_pcb
	(version 20241229)
	(generator "pcbnew")
	(generator_version "9.0")
	(general
		(thickness 1.711)
		(legacy_teardrops no)
	)
	(paper "A4")
	(title_block
		(title "Antmicro Baseboard for Jetson AGX Thor")
		(date "2026-02-18")
		(rev "1.1.0")
		(company "Antmicro Ltd")
		(comment 1 "www.antmicro.com")
		(comment 9 "footprints 642-645 of 1170")
	)
	(layers
		(0 "F.Cu" signal)
		(4 "In1.Cu" signal)
		(6 "In2.Cu" signal)
		(8 "In3.Cu" signal)
		(10 "In4.Cu" jumper)
		(12 "In5.Cu" signal)
		(14 "In6.Cu" signal)
		(16 "In7.Cu" signal)
		(18 "In8.Cu" signal)
		(2 "B.Cu" signal)
		(9 "F.Adhes" user "F.Adhesive")
		(11 "B.Adhes" user "B.Adhesive")
		(13 "F.Paste" user)
		(15 "B.Paste" user)
		(5 "F.SilkS" user "F.Silkscreen")
		(7 "B.SilkS" user "B.Silkscreen")
		(1 "F.Mask" user)
		(3 "B.Mask" user)
		(17 "Dwgs.User" user "User.Drawings")
		(19 "Cmts.User" user "User.Comments")
		(21 "Eco1.User" user "User.Eco1")
		(23 "Eco2.User" user "User.Eco2")
		(25 "Edge.Cuts" user)
		(27 "Margin" user)
		(31 "F.CrtYd" user "F.Courtyard")
		(29 "B.CrtYd" user "B.Courtyard")
		(35 "F.Fab" user)
		(33 "B.Fab" user)
	)
	(footprint "antmicro-footprints:XSON-8_1x1.95mm_P0.5mm"
		(layer "B.Cu")
		(at 199.4 66.4 90)
		(property "Reference" "U49"
			(at -1.21 -2.14 90)
			(layer "B.SilkS")
			(effects
				(font
					(size 0.7 0.7)
					(thickness 0.15)
				)
				(justify right top mirror)
			)
		)
		(property "Value" "NTS0102_XSON"
			(at 0 -2.2 90)
			(layer "B.Fab")
			(effects
				(font
					(size 0.7 0.7)
					(thickness 0.15)
				)
				(justify right top mirror)
			)
		)
		(property "Datasheet" "http://www.farnell.com/datasheets/1760723.pdf"
			(at 0 0 90)
			(layer "B.Fab")
			(hide yes)
			(effects
				(font
					(size 1.27 1.27)
					(thickness 0.15)
				)
				(justify mirror)
			)
		)
		(property "Description" "Transceiver, 1.65 V to 3.6 V, XSON-8"
			(at 0 0 90)
			(layer "B.Fab")
			(hide yes)
			(effects
				(font
					(size 1.27 1.27)
					(thickness 0.15)
				)
				(justify mirror)
			)
		)
		(property "MPN" "NTS0102GT"
			(at 0 0 270)
			(unlocked yes)
			(layer "B.Fab")
			(hide yes)
			(effects
				(font
					(size 1 1)
					(thickness 0.15)
				)
				(justify mirror)
			)
		)
		(property "Manufacturer" "NXP"
			(at 0 0 270)
			(unlocked yes)
			(layer "B.Fab")
			(hide yes)
			(effects
				(font
					(size 1 1)
					(thickness 0.15)
				)
				(justify mirror)
			)
		)
		(property "Author" "Antmicro"
			(at 0 0 270)
			(unlocked yes)
			(layer "B.Fab")
			(hide yes)
			(effects
				(font
					(size 1 1)
					(thickness 0.15)
				)
				(justify mirror)
			)
		)
		(property "License" "Apache-2.0"
			(at 0 0 270)
			(unlocked yes)
			(layer "B.Fab")
			(hide yes)
			(effects
				(font
					(size 1 1)
					(thickness 0.15)
				)
				(justify mirror)
			)
		)
		(sheetname "/CSI/")
		(sheetfile "csi.kicad_sch")
		(attr smd)
		(fp_line
			(start 0.5 -1.1)
			(end -0.5 -1.1)
			(stroke
				(width 0.15)
				(type solid)
			)
			(layer "B.SilkS")
		)
		(fp_line
			(start -0.5 1.1)
			(end 0.5 1.1)
			(stroke
				(width 0.15)
				(type solid)
			)
			(layer "B.SilkS")
		)
		(fp_circle
			(center -0.750001 1.1)
			(end -0.700999 1.1)
			(stroke
				(width 0.15)
				(type solid)
			)
			(fill no)
			(layer "B.SilkS")
		)
		(fp_poly
			(pts
				(xy -0.8 1.200001) (xy 0.8 1.200001) (xy 0.8 -1.200001) (xy -0.8 -1.200001)
			)
			(stroke
				(width 0.05)
				(type solid)
			)
			(fill no)
			(layer "B.CrtYd")
		)
		(fp_line
			(start 0.5305 -1)
			(end -0.5305 -1)
			(stroke
				(width 0.15)
				(type solid)
			)
			(layer "B.Fab")
		)
		(fp_line
			(start -0.5305 -1)
			(end -0.5305 1.001)
			(stroke
				(width 0.15)
				(type solid)
			)
			(layer "B.Fab")
		)
		(fp_line
			(start 0.5305 1.001)
			(end 0.5305 -1)
			(stroke
				(width 0.15)
				(type solid)
			)
			(layer "B.Fab")
		)
		(fp_line
			(start -0.5305 1.001)
			(end 0.5305 1.001)
			(stroke
				(width 0.15)
				(type solid)
			)
			(layer "B.Fab")
		)
		(fp_text user "Author: Antmicro"
			(at -0.527 -7.105 90)
			(layer "B.Fab")
			(effects
				(font
					(size 0.7 0.7)
					(thickness 0.15)
				)
				(justify right top mirror)
			)
		)
		(fp_text user "License: Apache-2.0"
			(at -0.527 -8.306 90)
			(layer "B.Fab")
			(effects
				(font
					(size 0.7 0.7)
					(thickness 0.15)
				)
				(justify right top mirror)
			)
		)
		(fp_text user "${REFERENCE}"
			(at -0.527 -5.905 90)
			(layer "B.Fab")
			(effects
				(font
					(size 0.7 0.7)
					(thickness 0.15)
				)
				(justify right top mirror)
			)
		)
		(pad "1" smd roundrect
			(at -0.45 0.75 270)
			(size 0.6 0.3)
			(layers "B.Cu" "B.Mask" "B.Paste")
			(roundrect_rratio 0.25)
			(net 210 "/CSI/VSYNC_CAM3_3V3")
			(pinfunction "B_{2}")
			(pintype "bidirectional")
		)
		(pad "2" smd roundrect
			(at -0.45 0.25 270)
			(size 0.6 0.25)
			(layers "B.Cu" "B.Mask" "B.Paste")
			(roundrect_rratio 0.25)
			(net 1 "GND")
			(pinfunction "GND")
			(pintype "power_in")
		)
		(pad "3" smd roundrect
			(at -0.45 -0.25 270)
			(size 0.6 0.25)
			(layers "B.Cu" "B.Mask" "B.Paste")
			(roundrect_rratio 0.25)
			(net 11 "+1V8")
			(pinfunction "VCC_{A}")
			(pintype "power_in")
		)
		(pad "4" smd roundrect
			(at -0.45 -0.75 270)
			(size 0.6 0.3)
			(layers "B.Cu" "B.Mask" "B.Paste")
			(roundrect_rratio 0.25)
			(net 47 "/CSI/CAM_CTRL.VSYNC_CAM3")
			(pinfunction "A_{2}")
			(pintype "bidirectional")
		)
		(pad "5" smd roundrect
			(at 0.45 -0.75 270)
			(size 0.6 0.3)
			(layers "B.Cu" "B.Mask" "B.Paste")
			(roundrect_rratio 0.25)
			(net 67 "/CSI/CAM_CTRL.VSYNC_CAM2")
			(pinfunction "A_{1}")
			(pintype "bidirectional")
		)
		(pad "6" smd roundrect
			(at 0.45 -0.25 270)
			(size 0.6 0.25)
			(layers "B.Cu" "B.Mask" "B.Paste")
			(roundrect_rratio 0.25)
			(net 11 "+1V8")
			(pinfunction "OE")
			(pintype "input")
		)
		(pad "7" smd roundrect
			(at 0.45 0.25 270)
			(size 0.6 0.25)
			(layers "B.Cu" "B.Mask" "B.Paste")
			(roundrect_rratio 0.25)
			(net 2 "+3V3")
			(pinfunction "VCC_{B}")
			(pintype "power_in")
		)
		(pad "8" smd roundrect
			(at 0.45 0.75 270)
			(size 0.6 0.3)
			(layers "B.Cu" "B.Mask" "B.Paste")
			(roundrect_rratio 0.25)
			(net 201 "/CSI/VSYNC_CAM2_3V3")
			(pinfunction "B_{1}")
			(pintype "bidirectional")
		)
	)
	(footprint "antmicro-footprints:R_0402_1005Metric"
		(layer "B.Cu")
		(at 175.568 62.37 90)
		(descr "Resistor SMD 0402")
		(tags "resistor SMD 0402")
		(property "Reference" "R233"
			(at -2.167516 0.699303 90)
			(layer "B.SilkS")
			(effects
				(font
					(size 0.7 0.7)
					(thickness 0.15)
				)
				(justify right top mirror)
			)
		)
		(property "Value" "R_100k_0402"
			(at -1.011843 -1.772047 90)
			(layer "B.Fab")
			(effects
				(font
					(size 0.7 0.7)
					(thickness 0.15)
				)
				(justify right top mirror)
			)
		)
		(property "Datasheet" "https://www.bourns.com/docs/product-datasheets/cr.pdf"
			(at 0 0 90)
			(layer "B.Fab")
			(hide yes)
			(effects
				(font
					(size 1.27 1.27)
					(thickness 0.15)
				)
				(justify mirror)
			)
		)
		(property "Description" "SMD Chip Resistor, 100 kohm, ± 1%, 62.5 mW, 0402 [1005 Metric], Thick Film, General Purpose"
			(at 0 0 90)
			(layer "B.Fab")
			(hide yes)
			(effects
				(font
					(size 1.27 1.27)
					(thickness 0.15)
				)
				(justify mirror)
			)
		)
		(property "Manufacturer" "Bourns"
			(at 0 0 270)
			(unlocked yes)
			(layer "B.Fab")
			(hide yes)
			(effects
				(font
					(size 1 1)
					(thickness 0.15)
				)
				(justify mirror)
			)
		)
		(property "MPN" "CR0402-FX-1003GLF"
			(at 0 0 270)
			(unlocked yes)
			(layer "B.Fab")
			(hide yes)
			(effects
				(font
					(size 1 1)
					(thickness 0.15)
				)
				(justify mirror)
			)
		)
		(property "Val" "100k"
			(at 0 0 270)
			(unlocked yes)
			(layer "B.Fab")
			(hide yes)
			(effects
				(font
					(size 1 1)
					(thickness 0.15)
				)
				(justify mirror)
			)
		)
		(property "License" "Apache-2.0"
			(at 0 0 270)
			(unlocked yes)
			(layer "B.Fab")
			(hide yes)
			(effects
				(font
					(size 1 1)
					(thickness 0.15)
				)
				(justify mirror)
			)
		)
		(property "Author" "Antmicro"
			(at 0 0 270)
			(unlocked yes)
			(layer "B.Fab")
			(hide yes)
			(effects
				(font
					(size 1 1)
					(thickness 0.15)
				)
				(justify mirror)
			)
		)
		(property "Tolerance" "1%"
			(at 0 0 270)
			(unlocked yes)
			(layer "B.Fab")
			(hide yes)
			(effects
				(font
					(size 1 1)
					(thickness 0.15)
				)
				(justify mirror)
			)
		)
		(sheetname "/Peripherals/")
		(sheetfile "peripherals.kicad_sch")
		(attr smd)
		(fp_rect
			(start -0.925 0.47)
			(end 0.925 -0.47)
			(stroke
				(width 0.05)
				(type default)
			)
			(fill no)
			(layer "B.CrtYd")
		)
		(fp_rect
			(start -0.5 0.25)
			(end 0.5 -0.25)
			(stroke
				(width 0.15)
				(type solid)
			)
			(fill no)
			(layer "B.Fab")
		)
		(fp_text user "Author: Antmicro"
			(at -0.95 -4.169 90)
			(layer "B.Fab")
			(effects
				(font
					(size 0.7 0.7)
					(thickness 0.15)
				)
				(justify right top mirror)
			)
		)
		(fp_text user "${REFERENCE}"
			(at -0.95 -3.168 90)
			(layer "B.Fab")
			(effects
				(font
					(size 0.7 0.7)
					(thickness 0.15)
				)
				(justify right top mirror)
			)
		)
		(fp_text user "License: Apache-2.0"
			(at -0.95 -5.169 90)
			(layer "B.Fab")
			(effects
				(font
					(size 0.7 0.7)
					(thickness 0.15)
				)
				(justify right top mirror)
			)
		)
		(pad "1" smd roundrect
			(at -0.48 0 90)
			(size 0.59 0.64)
			(layers "B.Cu" "B.Mask" "B.Paste")
			(roundrect_rratio 0.25)
			(net 1 "GND")
			(pintype "passive")
		)
		(pad "2" smd roundrect
			(at 0.48 0 90)
			(size 0.59 0.64)
			(layers "B.Cu" "B.Mask" "B.Paste")
			(roundrect_rratio 0.25)
			(net 371 "/Expansion connector/GPIO.USER_LED1")
			(pintype "passive")
		)
	)
	(footprint "antmicro-footprints:C_0402_1005Metric"
		(layer "B.Cu")
		(at 89.8 105.5 -90)
		(descr "Capacitor SMD 0402")
		(tags "capacitor SMD 0402")
		(property "Reference" "C329"
			(at 1 -0.5 90)
			(layer "B.SilkS")
			(effects
				(font
					(size 0.7 0.7)
					(thickness 0.15)
				)
				(justify left bottom mirror)
			)
		)
		(property "Value" "C_100n_0402"
			(at -1.022927 -2.155213 90)
			(layer "B.Fab")
			(effects
				(font
					(size 0.7 0.7)
					(thickness 0.15)
				)
				(justify left bottom mirror)
			)
		)
		(property "Datasheet" "https://www.murata.com/products/productdetail?partno=GRM155R61H104KE14%23"
			(at 0 0 90)
			(layer "B.Fab")
			(hide yes)
			(effects
				(font
					(size 1.27 1.27)
					(thickness 0.15)
				)
				(justify mirror)
			)
		)
		(property "Description" "SMD Multilayer Ceramic Capacitor, 0.1 µF, 50 V, 0402 [1005 Metric], ± 10%, X5R, GRM Series"
			(at 0 0 90)
			(layer "B.Fab")
			(hide yes)
			(effects
				(font
					(size 1.27 1.27)
					(thickness 0.15)
				)
				(justify mirror)
			)
		)
		(property "Manufacturer" "Murata"
			(at 0 0 90)
			(unlocked yes)
			(layer "B.Fab")
			(hide yes)
			(effects
				(font
					(size 1 1)
					(thickness 0.15)
				)
				(justify mirror)
			)
		)
		(property "MPN" "GRM155R61H104KE14D"
			(at 0 0 90)
			(unlocked yes)
			(layer "B.Fab")
			(hide yes)
			(effects
				(font
					(size 1 1)
					(thickness 0.15)
				)
				(justify mirror)
			)
		)
		(property "Val" "100n"
			(at 0 0 90)
			(unlocked yes)
			(layer "B.Fab")
			(hide yes)
			(effects
				(font
					(size 1 1)
					(thickness 0.15)
				)
				(justify mirror)
			)
		)
		(property "License" "Apache-2.0"
			(at 0 0 90)
			(unlocked yes)
			(layer "B.Fab")
			(hide yes)
			(effects
				(font
					(size 1 1)
					(thickness 0.15)
				)
				(justify mirror)
			)
		)
		(property "Author" "Antmicro"
			(at 0 0 90)
			(unlocked yes)
			(layer "B.Fab")
			(hide yes)
			(effects
				(font
					(size 1 1)
					(thickness 0.15)
				)
				(justify mirror)
			)
		)
		(property "Voltage" "50V"
			(at 0 0 90)
			(unlocked yes)
			(layer "B.Fab")
			(hide yes)
			(effects
				(font
					(size 1 1)
					(thickness 0.15)
				)
				(justify mirror)
			)
		)
		(property "Dielectric" "X5R"
			(at 0 0 90)
			(unlocked yes)
			(layer "B.Fab")
			(hide yes)
			(effects
				(font
					(size 1 1)
					(thickness 0.15)
				)
				(justify mirror)
			)
		)
		(sheetname "/SoM_IO2/")
		(sheetfile "som_io2.kicad_sch")
		(attr smd)
		(fp_poly
			(pts
				(xy -0.925 0.47) (xy 0.925 0.47) (xy 0.925 -0.47) (xy -0.925 -0.47)
			)
			(stroke
				(width 0.05)
				(type default)
			)
			(fill no)
			(layer "B.CrtYd")
		)
		(fp_line
			(start -0.494 0.25)
			(end 0.504 0.25)
			(stroke
				(width 0.15)
				(type solid)
			)
			(layer "B.Fab")
		)
		(fp_line
			(start 0.504 0.25)
			(end 0.504 -0.248)
			(stroke
				(width 0.15)
				(type solid)
			)
			(layer "B.Fab")
		)
		(fp_line
			(start -0.494 -0.248)
			(end -0.494 0.25)
			(stroke
				(width 0.15)
				(type solid)
			)
			(layer "B.Fab")
		)
		(fp_line
			(start 0.504 -0.248)
			(end -0.494 -0.248)
			(stroke
				(width 0.15)
				(type solid)
			)
			(layer "B.Fab")
		)
		(fp_text user "Author: Antmicro"
			(at -0.939 -3.399 90)
			(layer "B.Fab")
			(effects
				(font
					(size 0.7 0.7)
					(thickness 0.15)
				)
				(justify left bottom mirror)
			)
		)
		(fp_text user "License: Apache-2.0"
			(at -0.939 -5.799 90)
			(layer "B.Fab")
			(effects
				(font
					(size 0.7 0.7)
					(thickness 0.15)
				)
				(justify left bottom mirror)
			)
		)
		(fp_text user "${REFERENCE}"
			(at -0.939 -4.599 90)
			(layer "B.Fab")
			(effects
				(font
					(size 0.7 0.7)
					(thickness 0.15)
				)
				(justify left bottom mirror)
			)
		)
		(pad "1" smd roundrect
			(at -0.48 0 270)
			(size 0.59 0.64)
			(layers "B.Cu" "B.Mask" "B.Paste")
			(roundrect_rratio 0.25)
			(net 713 "/Expansion connector/DP1.TX1-")
			(pintype "passive")
		)
		(pad "2" smd roundrect
			(at 0.48 0 270)
			(size 0.59 0.64)
			(layers "B.Cu" "B.Mask" "B.Paste")
			(roundrect_rratio 0.25)
			(net 1249 "/SoM_IO2/DP1.TX1_C-")
			(pintype "passive")
		)
	)
	(footprint "antmicro-footprints:R_0402_1005Metric"
		(layer "B.Cu")
		(at 196.6 70.6 -90)
		(descr "Resistor SMD 0402")
		(tags "resistor SMD 0402")
		(property "Reference" "R112"
			(at -1.5 1.5 90)
			(layer "B.SilkS")
			(effects
				(font
					(size 0.7 0.7)
					(thickness 0.15)
				)
				(justify left bottom mirror)
			)
		)
		(property "Value" "R_0R_0402"
			(at -1.011843 -1.772046 90)
			(layer "B.Fab")
			(effects
				(font
					(size 0.7 0.7)
					(thickness 0.15)
				)
				(justify left bottom mirror)
			)
		)
		(property "Datasheet" "https://industrial.panasonic.com/cdbs/www-data/pdf/RDA0000/AOA0000C301.pdf"
			(at 0 0 90)
			(layer "B.Fab")
			(hide yes)
			(effects
				(font
					(size 1.27 1.27)
					(thickness 0.15)
				)
				(justify mirror)
			)
		)
		(property "Description" "SMD Chip Resistor, Jumper, 0 ohm, 100 mW, 0402 [1005 Metric], Thick Film, General Purpose"
			(at 0 0 90)
			(layer "B.Fab")
			(hide yes)
			(effects
				(font
					(size 1.27 1.27)
					(thickness 0.15)
				)
				(justify mirror)
			)
		)
		(property "Manufacturer" "Panasonic"
			(at 0 0 90)
			(unlocked yes)
			(layer "B.Fab")
			(hide yes)
			(effects
				(font
					(size 1 1)
					(thickness 0.15)
				)
				(justify mirror)
			)
		)
		(property "MPN" "ERJ2GE0R00X"
			(at 0 0 90)
			(unlocked yes)
			(layer "B.Fab")
			(hide yes)
			(effects
				(font
					(size 1 1)
					(thickness 0.15)
				)
				(justify mirror)
			)
		)
		(property "Val" "0R"
			(at 0 0 90)
			(unlocked yes)
			(layer "B.Fab")
			(hide yes)
			(effects
				(font
					(size 1 1)
					(thickness 0.15)
				)
				(justify mirror)
			)
		)
		(property "License" "Apache-2.0"
			(at 0 0 90)
			(unlocked yes)
			(layer "B.Fab")
			(hide yes)
			(effects
				(font
					(size 1 1)
					(thickness 0.15)
				)
				(justify mirror)
			)
		)
		(property "Author" "Antmicro"
			(at 0 0 90)
			(unlocked yes)
			(layer "B.Fab")
			(hide yes)
			(effects
				(font
					(size 1 1)
					(thickness 0.15)
				)
				(justify mirror)
			)
		)
		(property "Tolerance" "~"
			(at 0 0 90)
			(unlocked yes)
			(layer "B.Fab")
			(hide yes)
			(effects
				(font
					(size 1 1)
					(thickness 0.15)
				)
				(justify mirror)
			)
		)
		(property "Current" "1A"
			(at 0 0 90)
			(unlocked yes)
			(layer "B.Fab")
			(hide yes)
			(effects
				(font
					(size 1 1)
					(thickness 0.15)
				)
				(justify mirror)
			)
		)
		(sheetname "/USB Debug, PD/")
		(sheetfile "usb_debug_pd.kicad_sch")
		(attr smd)
		(fp_poly
			(pts
				(xy -0.925 0.47) (xy 0.925 0.47) (xy 0.925 -0.47) (xy -0.925 -0.47)
			)
			(stroke
				(width 0.05)
				(type default)
			)
			(fill no)
			(layer "B.CrtYd")
		)
		(fp_poly
			(pts
				(xy -0.5 0.25) (xy 0.5 0.25) (xy 0.5 -0.25) (xy -0.5 -0.25)
			)
			(stroke
				(width 0.15)
				(type solid)
			)
			(fill no)
			(layer "B.Fab")
		)
		(fp_text user "License: Apache-2.0"
			(at -0.949999 -5.169 90)
			(layer "B.Fab")
			(effects
				(font
					(size 0.7 0.7)
					(thickness 0.15)
				)
				(justify left bottom mirror)
			)
		)
		(fp_text user "${REFERENCE}"
			(at -0.95 -3.168 90)
			(layer "B.Fab")
			(effects
				(font
					(size 0.7 0.7)
					(thickness 0.15)
				)
				(justify left bottom mirror)
			)
		)
		(fp_text user "Author: Antmicro"
			(at -0.95 -4.169 90)
			(layer "B.Fab")
			(effects
				(font
					(size 0.7 0.7)
					(thickness 0.15)
				)
				(justify left bottom mirror)
			)
		)
		(pad "1" smd roundrect
			(at -0.48 0 270)
			(size 0.59 0.64)
			(layers "B.Cu" "B.Mask" "B.Paste")
			(roundrect_rratio 0.25)
			(net 850 "/I2C_{SYS}.SDA")
			(pintype "passive")
		)
		(pad "2" smd roundrect
			(at 0.48 0 270)
			(size 0.59 0.64)
			(layers "B.Cu" "B.Mask" "B.Paste")
			(roundrect_rratio 0.25)
			(net 946 "/USB Debug, PD/DEBUG_SDA")
			(pintype "passive")
		)
	)
)
